# T6G (Grand Teton) — schematic netlist excerpt (pin names and nets, part order shuffled) for the footprints in the layout excerpt that follows; sources: Cadence DE-HDL packaged netlist, KiCad conversion of 04192023_DAF0TMB3IC0_F0TG_MB_C_brd_V02_OCP.brd

C2536  Q_CAP  22UF 4V 20% X6S  pkg C0402  page 70 : A = PVDDCR_SOC_P0 ; B = GND
C973  Q_CAP  10UF 6.3V 20% X6S  pkg C0402  page 301 : A = P0V9_CPU0_RT2_2A ; B = GND

(kicad_pcb
	(version 20260206)
	(generator "pcbnew")
	(generator_version "10.0")
	(general
		(thickness 1.6)
		(legacy_teardrops no)
	)
	(paper "A4")
	(title_block
		(title "04192023_DAF0TMB3IC0_F0TG_MB_C_brd_V02_OCP.brd")
		(comment 1 "Grand Teton / footprints 5615-5616 of 8354")
	)
	(layers
		(0 "F.Cu" signal "TOP")
		(4 "In1.Cu" signal "GND")
		(6 "In2.Cu" signal "IN1")
		(8 "In3.Cu" signal "GND1")
		(10 "In4.Cu" signal "IN2")
		(12 "In5.Cu" signal "GND2")
		(14 "In6.Cu" signal "IN3")
		(16 "In7.Cu" signal "GND3")
		(18 "In8.Cu" signal "VCC")
		(20 "In9.Cu" signal "VCC1")
		(22 "In10.Cu" signal "GND4")
		(24 "In11.Cu" signal "IN4")
		(26 "In12.Cu" signal "GND5")
		(28 "In13.Cu" signal "IN5")
		(30 "In14.Cu" signal "GND6")
		(32 "In15.Cu" signal "IN6")
		(34 "In16.Cu" signal "GND7")
		(2 "B.Cu" signal "BOTTOM")
		(9 "F.Adhes" user "F.Adhesive")
		(11 "B.Adhes" user "B.Adhesive")
		(13 "F.Paste" user "Package Geometry/Pastemask Top")
		(15 "B.Paste" user "Package Geometry/Pastemask Bottom")
		(5 "F.SilkS" user "Ref Des/Silkscreen Top")
		(7 "B.SilkS" user "Ref Des/Silkscreen Bottom")
		(1 "F.Mask" user "Board Geometry/Soldermask Top")
		(3 "B.Mask" user "Board Geometry/Soldermask Bottom")
		(17 "Dwgs.User" user "User.Drawings")
		(19 "Cmts.User" user "User.Comments")
		(21 "Eco1.User" user "User.Eco1")
		(23 "Eco2.User" user "User.Eco2")
		(25 "Edge.Cuts" user "Board Geometry/Outline")
		(27 "Margin" user)
		(31 "F.CrtYd" user "Package Geometry/Place Bound Top")
		(29 "B.CrtYd" user "Package Geometry/Place Bound Bottom")
		(35 "F.Fab" user "Ref Des/Assembly Top")
		(33 "B.Fab" user "Ref Des/Assembly Bottom")
	)
	(footprint ""
		(layer "B.Cu")
		(at 361.645454 -251.78131)
		(property "Reference" "C2536"
			(at 0 0 0)
			(layer "B.SilkS")
			(hide yes)
			(effects
				(font
					(size 1.27 1.27)
				)
				(justify mirror)
			)
		)
		(property "Value" ""
			(at 0 0 0)
			(layer "B.Fab")
			(effects
				(font
					(size 1.27 1.27)
				)
				(justify mirror)
			)
		)
		(duplicate_pad_numbers_are_jumpers no)
		(fp_line
			(start -0.7874 -0.4064)
			(end -0.7874 0.4064)
			(stroke
				(width 0.1524)
				(type default)
			)
			(layer "B.SilkS")
		)
		(fp_line
			(start -0.7874 0.4064)
			(end 0.7874 0.4064)
			(stroke
				(width 0.1524)
				(type default)
			)
			(layer "B.SilkS")
		)
		(fp_line
			(start 0.7874 -0.4064)
			(end -0.7874 -0.4064)
			(stroke
				(width 0.1524)
				(type default)
			)
			(layer "B.SilkS")
		)
		(fp_line
			(start 0.7874 0.4064)
			(end 0.7874 -0.4064)
			(stroke
				(width 0.1524)
				(type default)
			)
			(layer "B.SilkS")
		)
		(fp_line
			(start -0.67945 -0.3048)
			(end -0.67945 0.3048)
			(stroke
				(width 0.1)
				(type default)
			)
			(layer "B.Fab")
		)
		(fp_line
			(start -0.67945 0.3048)
			(end -0.120396 0.3048)
			(stroke
				(width 0.1)
				(type default)
			)
			(layer "B.Fab")
		)
		(fp_line
			(start -0.12065 -0.3048)
			(end -0.67945 -0.3048)
			(stroke
				(width 0.1)
				(type default)
			)
			(layer "B.Fab")
		)
		(fp_line
			(start -0.12065 -0.2794)
			(end -0.12065 -0.3048)
			(stroke
				(width 0.1)
				(type default)
			)
			(layer "B.Fab")
		)
		(fp_line
			(start -0.120396 0.2794)
			(end 0.12065 0.2794)
			(stroke
				(width 0.1)
				(type default)
			)
			(layer "B.Fab")
		)
		(fp_line
			(start -0.120396 0.3048)
			(end -0.120396 0.2794)
			(stroke
				(width 0.1)
				(type default)
			)
			(layer "B.Fab")
		)
		(fp_line
			(start 0.12065 -0.305054)
			(end 0.12065 -0.2794)
			(stroke
				(width 0.1)
				(type default)
			)
			(layer "B.Fab")
		)
		(fp_line
			(start 0.12065 -0.2794)
			(end -0.12065 -0.2794)
			(stroke
				(width 0.1)
				(type default)
			)
			(layer "B.Fab")
		)
		(fp_line
			(start 0.12065 0.2794)
			(end 0.12065 0.3048)
			(stroke
				(width 0.1)
				(type default)
			)
			(layer "B.Fab")
		)
		(fp_line
			(start 0.12065 0.3048)
			(end 0.67945 0.3048)
			(stroke
				(width 0.1)
				(type default)
			)
			(layer "B.Fab")
		)
		(fp_line
			(start 0.67945 -0.305054)
			(end 0.12065 -0.305054)
			(stroke
				(width 0.1)
				(type default)
			)
			(layer "B.Fab")
		)
		(fp_line
			(start 0.67945 0.3048)
			(end 0.67945 -0.305054)
			(stroke
				(width 0.1)
				(type default)
			)
			(layer "B.Fab")
		)
		(pad "1" smd circle
			(at 0.40005 0 180)
			(size 0 0)
			(layers "B.Cu" "B.Mask" "B.Paste")
			(net "PVDDCR_SOC_P0")
		)
		(pad "2" smd circle
			(at -0.40005 0 180)
			(size 0 0)
			(layers "B.Cu" "B.Mask" "B.Paste")
			(net "GND")
		)
	)
	(footprint ""
		(layer "B.Cu")
		(at 417.419028 -398.942052 90)
		(property "Reference" "C973"
			(at 0 0 90)
			(layer "B.SilkS")
			(hide yes)
			(effects
				(font
					(size 1.27 1.27)
				)
				(justify mirror)
			)
		)
		(property "Value" ""
			(at 0 0 90)
			(layer "B.Fab")
			(effects
				(font
					(size 1.27 1.27)
				)
				(justify mirror)
			)
		)
		(duplicate_pad_numbers_are_jumpers no)
		(fp_line
			(start 0.7874 -0.4064)
			(end -0.7874 -0.4064)
			(stroke
				(width 0.1524)
				(type default)
			)
			(layer "B.SilkS")
		)
		(fp_line
			(start -0.7874 -0.4064)
			(end -0.7874 0.4064)
			(stroke
				(width 0.1524)
				(type default)
			)
			(layer "B.SilkS")
		)
		(fp_line
			(start 0.7874 0.4064)
			(end 0.7874 -0.4064)
			(stroke
				(width 0.1524)
				(type default)
			)
			(layer "B.SilkS")
		)
		(fp_line
			(start -0.7874 0.4064)
			(end 0.7874 0.4064)
			(stroke
				(width 0.1524)
				(type default)
			)
			(layer "B.SilkS")
		)
		(fp_line
			(start 0.67945 -0.305054)
			(end 0.12065 -0.305054)
			(stroke
				(width 0.1)
				(type default)
			)
			(layer "B.Fab")
		)
		(fp_line
			(start 0.12065 -0.305054)
			(end 0.12065 -0.2794)
			(stroke
				(width 0.1)
				(type default)
			)
			(layer "B.Fab")
		)
		(fp_line
			(start -0.12065 -0.3048)
			(end -0.67945 -0.3048)
			(stroke
				(width 0.1)
				(type default)
			)
			(layer "B.Fab")
		)
		(fp_line
			(start -0.67945 -0.3048)
			(end -0.67945 0.3048)
			(stroke
				(width 0.1)
				(type default)
			)
			(layer "B.Fab")
		)
		(fp_line
			(start 0.12065 -0.2794)
			(end -0.12065 -0.2794)
			(stroke
				(width 0.1)
				(type default)
			)
			(layer "B.Fab")
		)
		(fp_line
			(start -0.12065 -0.2794)
			(end -0.12065 -0.3048)
			(stroke
				(width 0.1)
				(type default)
			)
			(layer "B.Fab")
		)
		(fp_line
			(start 0.12065 0.2794)
			(end 0.12065 0.3048)
			(stroke
				(width 0.1)
				(type default)
			)
			(layer "B.Fab")
		)
		(fp_line
			(start -0.120396 0.2794)
			(end 0.12065 0.2794)
			(stroke
				(width 0.1)
				(type default)
			)
			(layer "B.Fab")
		)
		(fp_line
			(start 0.67945 0.3048)
			(end 0.67945 -0.305054)
			(stroke
				(width 0.1)
				(type default)
			)
			(layer "B.Fab")
		)
		(fp_line
			(start 0.12065 0.3048)
			(end 0.67945 0.3048)
			(stroke
				(width 0.1)
				(type default)
			)
			(layer "B.Fab")
		)
		(fp_line
			(start -0.120396 0.3048)
			(end -0.120396 0.2794)
			(stroke
				(width 0.1)
				(type default)
			)
			(layer "B.Fab")
		)
		(fp_line
			(start -0.67945 0.3048)
			(end -0.120396 0.3048)
			(stroke
				(width 0.1)
				(type default)
			)
			(layer "B.Fab")
		)
		(pad "1" smd circle
			(at 0.40005 0 270)
			(size 0 0)
			(layers "B.Cu" "B.Mask" "B.Paste")
			(net "P0V9_CPU0_RT2_2A")
		)
		(pad "2" smd circle
			(at -0.40005 0 270)
			(size 0 0)
			(layers "B.Cu" "B.Mask" "B.Paste")
			(net "GND")
		)
	)
)
